(kicad_pcb
	(version 20260206)
	(generator "pcbnew")
	(generator_version "10.0")
	(general
		(thickness 1.6)
		(legacy_teardrops no)
	)
	(paper "A4")
	(title_block
		(title "Bryce Canyon_SCC_16316-1_OCP.brd")
		(comment 1 "Bryce Canyon / footprints 548-554 of 1561")
	)
	(layers
		(0 "F.Cu" signal "TOP")
		(4 "In1.Cu" signal "L2GND")
		(6 "In2.Cu" signal "L3")
		(8 "In3.Cu" signal "L4VCC")
		(10 "In4.Cu" signal "L5VCC")
		(12 "In5.Cu" signal "L6")
		(14 "In6.Cu" signal "L7GND")
		(2 "B.Cu" signal "BOTTOM")
		(9 "F.Adhes" user "F.Adhesive")
		(11 "B.Adhes" user "B.Adhesive")
		(13 "F.Paste" user "Package Geometry/Pastemask Top")
		(15 "B.Paste" user "Package Geometry/Pastemask Bottom")
		(5 "F.SilkS" user "Ref Des/Silkscreen Top")
		(7 "B.SilkS" user "Ref Des/Silkscreen Bottom")
		(1 "F.Mask" user "Board Geometry/Soldermask Top")
		(3 "B.Mask" user "Board Geometry/Soldermask Bottom")
		(17 "Dwgs.User" user "User.Drawings")
		(19 "Cmts.User" user "User.Comments")
		(21 "Eco1.User" user "User.Eco1")
		(23 "Eco2.User" user "User.Eco2")
		(25 "Edge.Cuts" user "Board Geometry/Outline")
		(27 "Margin" user)
		(31 "F.CrtYd" user "Package Geometry/Place Bound Top")
		(29 "B.CrtYd" user "Package Geometry/Place Bound Bottom")
		(35 "F.Fab" user "Ref Des/Assembly Top")
		(33 "B.Fab" user "Ref Des/Assembly Bottom")
	)
	(footprint ""
		(layer "F.Cu")
		(at 17.0307 -93.408754 90)
		(property "Reference" "R410"
			(at 0 0 90)
			(layer "F.SilkS")
			(hide yes)
			(effects
				(font
					(size 1.27 1.27)
				)
			)
		)
		(property "Value" "0R2J-2-GP"
			(at 0.064008 -3.993896 90)
			(unlocked yes)
			(layer "F.Fab")
			(hide yes)
			(effects
				(font
					(size 1.016 1.016)
					(thickness 0.1524)
				)
			)
		)
		(property "Device Type" "R402H16"
			(at 0.064008 -5.517896 90)
			(unlocked yes)
			(layer "F.Fab")
			(hide yes)
			(effects
				(font
					(size 1.016 1.016)
					(thickness 0.1524)
				)
			)
		)
		(duplicate_pad_numbers_are_jumpers no)
		(fp_line
			(start 0.508 -0.9398)
			(end -0.508 -0.9398)
			(stroke
				(width 0.1524)
				(type default)
			)
			(layer "F.SilkS")
		)
		(fp_line
			(start -0.508 -0.9398)
			(end -0.508 0.9398)
			(stroke
				(width 0.1524)
				(type default)
			)
			(layer "F.SilkS")
		)
		(fp_rect
			(start -0.508 0.9398)
			(end 0.508 -0.9398)
			(stroke
				(width 0)
				(type default)
			)
			(fill no)
			(layer "F.CrtYd")
		)
		(fp_rect
			(start -0.508 0.9398)
			(end 0.508 -0.9398)
			(stroke
				(width 0)
				(type default)
			)
			(fill no)
			(layer "F.Fab")
		)
		(pad "1" smd custom
			(at 0 -0.4445 90)
			(size 0.1397 0.1397)
			(layers "F.Cu" "F.Mask" "F.Paste")
			(net "LS_EN_U35")
			(options
				(clearance outline)
				(anchor circle)
			)
			(primitives
				(gr_poly
					(pts
						(arc
							(start -0.1778 -0.2794)
							(mid -0.249642 -0.249642)
							(end -0.2794 -0.1778)
						)
						(arc
							(start -0.2794 0.1778)
							(mid -0.249642 0.249642)
							(end -0.1778 0.2794)
						)
						(arc
							(start 0.1778 0.2794)
							(mid 0.249642 0.249642)
							(end 0.2794 0.1778)
						)
						(arc
							(start 0.2794 -0.1778)
							(mid 0.249642 -0.249642)
							(end 0.1778 -0.2794)
						)
					)
					(width 0)
					(fill yes)
				)
			)
		)
		(pad "2" smd custom
			(at 0 0.4445 90)
			(size 0.1397 0.1397)
			(layers "F.Cu" "F.Mask" "F.Paste")
			(net "VREF0")
			(options
				(clearance outline)
				(anchor circle)
			)
			(primitives
				(gr_poly
					(pts
						(arc
							(start -0.1778 -0.2794)
							(mid -0.249642 -0.249642)
							(end -0.2794 -0.1778)
						)
						(arc
							(start -0.2794 0.1778)
							(mid -0.249642 0.249642)
							(end -0.1778 0.2794)
						)
						(arc
							(start 0.1778 0.2794)
							(mid 0.249642 0.249642)
							(end 0.2794 0.1778)
						)
						(arc
							(start 0.2794 -0.1778)
							(mid 0.249642 -0.249642)
							(end 0.1778 -0.2794)
						)
					)
					(width 0)
					(fill yes)
				)
			)
		)
	)
	(footprint ""
		(layer "F.Cu")
		(at 70.866 -81.6864 -90)
		(property "Reference" "R584"
			(at 0 0 270)
			(layer "F.SilkS")
			(hide yes)
			(effects
				(font
					(size 1.27 1.27)
				)
			)
		)
		(property "Value" "0R2J-2-GP"
			(at 0.064008 -3.993896 270)
			(unlocked yes)
			(layer "F.Fab")
			(hide yes)
			(effects
				(font
					(size 1.016 1.016)
					(thickness 0.1524)
				)
			)
		)
		(property "Device Type" "R402H16"
			(at 0.064008 -5.517896 270)
			(unlocked yes)
			(layer "F.Fab")
			(hide yes)
			(effects
				(font
					(size 1.016 1.016)
					(thickness 0.1524)
				)
			)
		)
		(duplicate_pad_numbers_are_jumpers no)
		(fp_line
			(start -0.508 -0.9398)
			(end -0.508 0.9398)
			(stroke
				(width 0.1524)
				(type default)
			)
			(layer "F.SilkS")
		)
		(fp_line
			(start 0.508 -0.9398)
			(end -0.508 -0.9398)
			(stroke
				(width 0.1524)
				(type default)
			)
			(layer "F.SilkS")
		)
		(fp_rect
			(start -0.508 0.9398)
			(end 0.508 -0.9398)
			(stroke
				(width 0)
				(type default)
			)
			(fill no)
			(layer "F.CrtYd")
		)
		(fp_rect
			(start -0.508 0.9398)
			(end 0.508 -0.9398)
			(stroke
				(width 0)
				(type default)
			)
			(fill no)
			(layer "F.Fab")
		)
		(pad "1" smd custom
			(at 0 -0.4445 270)
			(size 0.1397 0.1397)
			(layers "F.Cu" "F.Mask" "F.Paste")
			(net "P1V8_E")
			(options
				(clearance outline)
				(anchor circle)
			)
			(primitives
				(gr_poly
					(pts
						(arc
							(start -0.1778 -0.2794)
							(mid -0.249642 -0.249642)
							(end -0.2794 -0.1778)
						)
						(arc
							(start -0.2794 0.1778)
							(mid -0.249642 0.249642)
							(end -0.1778 0.2794)
						)
						(arc
							(start 0.1778 0.2794)
							(mid 0.249642 0.249642)
							(end 0.2794 0.1778)
						)
						(arc
							(start 0.2794 -0.1778)
							(mid 0.249642 -0.249642)
							(end 0.1778 -0.2794)
						)
					)
					(width 0)
					(fill yes)
				)
			)
		)
		(pad "2" smd custom
			(at 0 0.4445 270)
			(size 0.1397 0.1397)
			(layers "F.Cu" "F.Mask" "F.Paste")
			(net "U122_VCC")
			(options
				(clearance outline)
				(anchor circle)
			)
			(primitives
				(gr_poly
					(pts
						(arc
							(start -0.1778 -0.2794)
							(mid -0.249642 -0.249642)
							(end -0.2794 -0.1778)
						)
						(arc
							(start -0.2794 0.1778)
							(mid -0.249642 0.249642)
							(end -0.1778 0.2794)
						)
						(arc
							(start 0.1778 0.2794)
							(mid 0.249642 0.249642)
							(end 0.2794 0.1778)
						)
						(arc
							(start 0.2794 -0.1778)
							(mid 0.249642 -0.249642)
							(end 0.1778 -0.2794)
						)
					)
					(width 0)
					(fill yes)
				)
			)
		)
	)
	(footprint ""
		(layer "F.Cu")
		(at 192.829434 -36.480496 -90)
		(property "Reference" "R189"
			(at 0 0 270)
			(layer "F.SilkS")
			(hide yes)
			(effects
				(font
					(size 1.27 1.27)
				)
			)
		)
		(property "Value" "2K2R2F-GP"
			(at 0.064008 -3.993896 270)
			(unlocked yes)
			(layer "F.Fab")
			(hide yes)
			(effects
				(font
					(size 1.016 1.016)
					(thickness 0.1524)
				)
			)
		)
		(property "Device Type" "R402H16"
			(at 0.064008 -5.517896 270)
			(unlocked yes)
			(layer "F.Fab")
			(hide yes)
			(effects
				(font
					(size 1.016 1.016)
					(thickness 0.1524)
				)
			)
		)
		(duplicate_pad_numbers_are_jumpers no)
		(fp_line
			(start -0.508 -0.9398)
			(end -0.508 0.9398)
			(stroke
				(width 0.1524)
				(type default)
			)
			(layer "F.SilkS")
		)
		(fp_line
			(start 0.508 -0.9398)
			(end -0.508 -0.9398)
			(stroke
				(width 0.1524)
				(type default)
			)
			(layer "F.SilkS")
		)
		(fp_rect
			(start -0.508 0.9398)
			(end 0.508 -0.9398)
			(stroke
				(width 0)
				(type default)
			)
			(fill no)
			(layer "F.CrtYd")
		)
		(fp_rect
			(start -0.508 0.9398)
			(end 0.508 -0.9398)
			(stroke
				(width 0)
				(type default)
			)
			(fill no)
			(layer "F.Fab")
		)
		(pad "1" smd custom
			(at 0 -0.4445 270)
			(size 0.1397 0.1397)
			(layers "F.Cu" "F.Mask" "F.Paste")
			(net "P1V8_C")
			(options
				(clearance outline)
				(anchor circle)
			)
			(primitives
				(gr_poly
					(pts
						(arc
							(start -0.1778 -0.2794)
							(mid -0.249642 -0.249642)
							(end -0.2794 -0.1778)
						)
						(arc
							(start -0.2794 0.1778)
							(mid -0.249642 0.249642)
							(end -0.1778 0.2794)
						)
						(arc
							(start 0.1778 0.2794)
							(mid 0.249642 0.249642)
							(end 0.2794 0.1778)
						)
						(arc
							(start 0.2794 -0.1778)
							(mid 0.249642 -0.249642)
							(end 0.1778 -0.2794)
						)
					)
					(width 0)
					(fill yes)
				)
			)
		)
		(pad "2" smd custom
			(at 0 0.4445 270)
			(size 0.1397 0.1397)
			(layers "F.Cu" "F.Mask" "F.Paste")
			(net "I2C_IOC_3_SDA")
			(options
				(clearance outline)
				(anchor circle)
			)
			(primitives
				(gr_poly
					(pts
						(arc
							(start -0.1778 -0.2794)
							(mid -0.249642 -0.249642)
							(end -0.2794 -0.1778)
						)
						(arc
							(start -0.2794 0.1778)
							(mid -0.249642 0.249642)
							(end -0.1778 0.2794)
						)
						(arc
							(start 0.1778 0.2794)
							(mid 0.249642 0.249642)
							(end 0.2794 0.1778)
						)
						(arc
							(start 0.2794 -0.1778)
							(mid 0.249642 -0.249642)
							(end 0.1778 -0.2794)
						)
					)
					(width 0)
					(fill yes)
				)
			)
		)
	)
	(footprint ""
		(layer "F.Cu")
		(at 19.252184 -72.82053 90)
		(property "Reference" "R356"
			(at 0 0 90)
			(layer "F.SilkS")
			(hide yes)
			(effects
				(font
					(size 1.27 1.27)
				)
			)
		)
		(property "Value" "8K2R2J-3-GP"
			(at 0.064008 -3.993896 90)
			(unlocked yes)
			(layer "F.Fab")
			(hide yes)
			(effects
				(font
					(size 1.016 1.016)
					(thickness 0.1524)
				)
			)
		)
		(property "Device Type" "R402H16"
			(at 0.064008 -5.517896 90)
			(unlocked yes)
			(layer "F.Fab")
			(hide yes)
			(effects
				(font
					(size 1.016 1.016)
					(thickness 0.1524)
				)
			)
		)
		(duplicate_pad_numbers_are_jumpers no)
		(fp_line
			(start 0.508 -0.9398)
			(end -0.508 -0.9398)
			(stroke
				(width 0.1524)
				(type default)
			)
			(layer "F.SilkS")
		)
		(fp_line
			(start -0.508 -0.9398)
			(end -0.508 0.9398)
			(stroke
				(width 0.1524)
				(type default)
			)
			(layer "F.SilkS")
		)
		(fp_rect
			(start -0.508 0.9398)
			(end 0.508 -0.9398)
			(stroke
				(width 0)
				(type default)
			)
			(fill no)
			(layer "F.CrtYd")
		)
		(fp_rect
			(start -0.508 0.9398)
			(end 0.508 -0.9398)
			(stroke
				(width 0)
				(type default)
			)
			(fill no)
			(layer "F.Fab")
		)
		(pad "1" smd custom
			(at 0 -0.4445 90)
			(size 0.1397 0.1397)
			(layers "F.Cu" "F.Mask" "F.Paste")
			(net "EEPROM_WP")
			(options
				(clearance outline)
				(anchor circle)
			)
			(primitives
				(gr_poly
					(pts
						(arc
							(start -0.1778 -0.2794)
							(mid -0.249642 -0.249642)
							(end -0.2794 -0.1778)
						)
						(arc
							(start -0.2794 0.1778)
							(mid -0.249642 0.249642)
							(end -0.1778 0.2794)
						)
						(arc
							(start 0.1778 0.2794)
							(mid 0.249642 0.249642)
							(end 0.2794 0.1778)
						)
						(arc
							(start 0.2794 -0.1778)
							(mid 0.249642 -0.249642)
							(end 0.1778 -0.2794)
						)
					)
					(width 0)
					(fill yes)
				)
			)
		)
		(pad "2" smd custom
			(at 0 0.4445 90)
			(size 0.1397 0.1397)
			(layers "F.Cu" "F.Mask" "F.Paste")
			(net "GND")
			(options
				(clearance outline)
				(anchor circle)
			)
			(primitives
				(gr_poly
					(pts
						(arc
							(start -0.1778 -0.2794)
							(mid -0.249642 -0.249642)
							(end -0.2794 -0.1778)
						)
						(arc
							(start -0.2794 0.1778)
							(mid -0.249642 0.249642)
							(end -0.1778 0.2794)
						)
						(arc
							(start 0.1778 0.2794)
							(mid 0.249642 0.249642)
							(end 0.2794 0.1778)
						)
						(arc
							(start 0.2794 -0.1778)
							(mid 0.249642 -0.249642)
							(end 0.1778 -0.2794)
						)
					)
					(width 0)
					(fill yes)
				)
			)
		)
	)
	(footprint ""
		(layer "F.Cu")
		(at 176.6824 -57.785)
		(property "Reference" "TP140"
			(at 0 0 0)
			(layer "F.SilkS")
			(hide yes)
			(effects
				(font
					(size 1.27 1.27)
				)
			)
		)
		(property "Value" "TPAD28-2-GP"
			(at -0.0127 -1.6637 0)
			(unlocked yes)
			(layer "F.Fab")
			(hide yes)
			(effects
				(font
					(size 1.016 1.016)
					(thickness 0.1524)
				)
			)
		)
		(property "Device Type" "TPAD28"
			(at -0.0127 -3.1877 0)
			(unlocked yes)
			(layer "F.Fab")
			(hide yes)
			(effects
				(font
					(size 1.016 1.016)
					(thickness 0.1524)
				)
			)
		)
		(duplicate_pad_numbers_are_jumpers no)
		(fp_poly
			(pts
				(arc
					(start 0.3556 0)
					(mid -0.3556 0)
					(end 0.3556 0)
				)
			)
			(stroke
				(width 0)
				(type default)
			)
			(fill no)
			(layer "F.CrtYd")
		)
		(fp_poly
			(pts
				(arc
					(start 0.6096 0)
					(mid -0.6096 0)
					(end 0.6096 0)
				)
			)
			(stroke
				(width 0)
				(type default)
			)
			(fill no)
			(layer "F.Fab")
		)
		(pad "1" smd circle
			(at 0 0)
			(size 0.7112 0.7112)
			(layers "F.Cu" "F.Mask" "F.Paste")
			(net "LSI_SCAN_EN")
		)
	)
	(footprint ""
		(layer "F.Cu")
		(at 153.924 -110.49 180)
		(property "Reference" "R379"
			(at 0 0 180)
			(layer "F.SilkS")
			(hide yes)
			(effects
				(font
					(size 1.27 1.27)
				)
			)
		)
		(property "Value" "3D01R5F-GP"
			(at 0 -8.9535 180)
			(unlocked yes)
			(layer "F.Fab")
			(hide yes)
			(effects
				(font
					(size 1.27 1.016)
					(thickness 0.1524)
				)
			)
		)
		(property "Device Type" "R805H24"
			(at 0 -10.6299 180)
			(unlocked yes)
			(layer "F.Fab")
			(hide yes)
			(effects
				(font
					(size 1.27 1.016)
					(thickness 0.1524)
				)
			)
		)
		(duplicate_pad_numbers_are_jumpers no)
		(fp_line
			(start 0.889 1.7018)
			(end 0.889 -0.508)
			(stroke
				(width 0.1524)
				(type default)
			)
			(layer "F.SilkS")
		)
		(fp_line
			(start 0.889 -1.7018)
			(end 0.889 -0.381)
			(stroke
				(width 0.1524)
				(type default)
			)
			(layer "F.SilkS")
		)
		(fp_line
			(start 0.889 -1.7018)
			(end -0.889 -1.7018)
			(stroke
				(width 0.1524)
				(type default)
			)
			(layer "F.SilkS")
		)
		(fp_line
			(start -0.889 1.7018)
			(end 0.889 1.7018)
			(stroke
				(width 0.1524)
				(type default)
			)
			(layer "F.SilkS")
		)
		(fp_line
			(start -0.889 0.0762)
			(end -0.889 1.7018)
			(stroke
				(width 0.1524)
				(type default)
			)
			(layer "F.SilkS")
		)
		(fp_line
			(start -0.889 -1.7018)
			(end -0.889 0.2794)
			(stroke
				(width 0.1524)
				(type default)
			)
			(layer "F.SilkS")
		)
		(fp_poly
			(pts
				(xy 0.9652 -1.778) (xy 0.9652 1.778) (xy -0.9652 1.778) (xy -0.9652 -1.778)
			)
			(stroke
				(width 0)
				(type default)
			)
			(fill no)
			(layer "F.CrtYd")
		)
		(fp_rect
			(start -0.9652 1.778)
			(end 0.9652 -1.778)
			(stroke
				(width 0)
				(type default)
			)
			(fill no)
			(layer "F.Fab")
		)
		(pad "1" smd rect
			(at 0 -0.9652 180)
			(size 1.397 1.143)
			(layers "F.Cu" "F.Mask" "F.Paste")
			(net "P1V5_E_SNB")
		)
		(pad "2" smd rect
			(at 0 0.9652 180)
			(size 1.397 1.143)
			(layers "F.Cu" "F.Mask" "F.Paste")
			(net "GND")
		)
	)
	(footprint ""
		(layer "F.Cu")
		(at 16.0528 -34.4678 90)
		(property "Reference" "R14"
			(at 0 0 90)
			(layer "F.SilkS")
			(hide yes)
			(effects
				(font
					(size 1.27 1.27)
				)
			)
		)
		(property "Value" "D003R0612F-L-GP"
			(at 3.2766 1.3843 90)
			(unlocked yes)
			(layer "F.Fab")
			(hide yes)
			(effects
				(font
					(size 1.016 1.016)
					(thickness 0.1524)
				)
			)
		)
		(property "Device Type" "RL3115-4PH25"
			(at 3.2766 -0.1397 90)
			(unlocked yes)
			(layer "F.Fab")
			(hide yes)
			(effects
				(font
					(size 1.016 1.016)
					(thickness 0.1524)
				)
			)
		)
		(duplicate_pad_numbers_are_jumpers no)
		(fp_line
			(start -0.5461 -1.778)
			(end -2.0828 -1.778)
			(stroke
				(width 0.3302)
				(type default)
			)
			(layer "F.SilkS")
		)
		(fp_line
			(start -2.0828 -1.778)
			(end -2.0828 -0.4445)
			(stroke
				(width 0.3302)
				(type default)
			)
			(layer "F.SilkS")
		)
		(fp_line
			(start 1.9685 -1.651)
			(end 1.9685 1.651)
			(stroke
				(width 0.1524)
				(type default)
			)
			(layer "F.SilkS")
		)
		(fp_line
			(start -1.9685 -1.651)
			(end 1.9685 -1.651)
			(stroke
				(width 0.1524)
				(type default)
			)
			(layer "F.SilkS")
		)
		(fp_line
			(start 1.9685 1.651)
			(end -1.9685 1.651)
			(stroke
				(width 0.1524)
				(type default)
			)
			(layer "F.SilkS")
		)
		(fp_line
			(start -1.9685 1.651)
			(end -1.9685 -1.651)
			(stroke
				(width 0.1524)
				(type default)
			)
			(layer "F.SilkS")
		)
		(fp_poly
			(pts
				(xy -0.561594 -1.726946) (xy -0.053594 -2.234946) (xy -1.069594 -2.234946)
			)
			(stroke
				(width 0)
				(type default)
			)
			(fill yes)
			(layer "F.SilkS")
		)
		(fp_rect
			(start -1.524 0.7493)
			(end 1.524 -0.7493)
			(stroke
				(width 0)
				(type default)
			)
			(fill no)
			(layer "F.CrtYd")
		)
		(fp_poly
			(pts
				(xy -2.2225 1.905) (xy -2.2225 -1.905) (xy 2.2225 -1.905) (xy 2.2225 -0.7493) (xy -1.524 -0.7493)
				(xy -1.524 0.7493) (xy 1.524 0.7493) (xy 1.524 -0.7366) (xy 2.2225 -0.7366) (xy 2.2225 1.905)
			)
			(stroke
				(width 0)
				(type default)
			)
			(fill no)
			(layer "F.CrtYd")
		)
		(fp_rect
			(start -2.2225 1.905)
			(end 2.2225 -1.905)
			(stroke
				(width 0)
				(type default)
			)
			(fill no)
			(layer "F.Fab")
		)
		(pad "1" smd rect
			(at -0.5715 -0.813562 90)
			(size 2.286 1.143)
			(layers "F.Cu" "F.Mask" "F.Paste")
			(net "MB0_P12V_MAIN_R")
		)
		(pad "2" smd rect
			(at -0.5715 0.813562 90)
			(size 2.286 1.143)
			(layers "F.Cu" "F.Mask" "F.Paste")
			(net "P12V_MAIN")
		)
		(pad "3" smd rect
			(at 1.334008 -0.813562 90)
			(size 0.762 1.143)
			(layers "F.Cu" "F.Mask" "F.Paste")
			(net "MB0_CM_SENSE_R1_N")
		)
		(pad "4" smd rect
			(at 1.334008 0.813562 90)
			(size 0.762 1.143)
			(layers "F.Cu" "F.Mask" "F.Paste")
			(net "MB0_CM_SENSE_R1_P")
		)
		(zone
			(layer "F.Cu")
			(hatch none 0.5)
			(connect_pads
				(clearance 0)
			)
			(min_thickness 0.25)
			(keepout
				(tracks allowed)
				(vias not_allowed)
				(pads allowed)
				(copperpour not_allowed)
				(footprints allowed)
			)
			(placement
				(enabled no)
				(sheetname "")
			)
			(fill
				(thermal_gap 0.5)
				(thermal_bridge_width 0.5)
				(island_removal_mode 0)
			)
			(polygon
				(pts
					(xy 15.810738 -35.0393) (xy 15.810738 -35.420808) (xy 15.3035 -35.420808) (xy 15.3035 -35.0393)
				)
			)
		)
		(zone
			(layer "F.Cu")
			(hatch none 0.5)
			(connect_pads
				(clearance 0)
			)
			(min_thickness 0.25)
			(keepout
				(tracks not_allowed)
				(vias allowed)
				(pads allowed)
				(copperpour not_allowed)
				(footprints allowed)
			)
			(placement
				(enabled no)
				(sheetname "")
			)
			(fill
				(thermal_gap 0.5)
				(thermal_bridge_width 0.5)
				(island_removal_mode 0)
			)
			(polygon
				(pts
					(xy 15.810738 -35.0393) (xy 15.810738 -35.420808) (xy 15.3035 -35.420808) (xy 15.3035 -35.0393)
				)
			)
		)
		(zone
			(layer "F.Cu")
			(hatch none 0.5)
			(connect_pads
				(clearance 0)
			)
			(min_thickness 0.25)
			(keepout
				(tracks allowed)
				(vias not_allowed)
				(pads allowed)
				(copperpour not_allowed)
				(footprints allowed)
			)
			(placement
				(enabled no)
				(sheetname "")
			)
			(fill
				(thermal_gap 0.5)
				(thermal_bridge_width 0.5)
				(island_removal_mode 0)
			)
			(polygon
				(pts
					(xy 16.8021 -35.0393) (xy 16.8021 -35.420808) (xy 16.294862 -35.420808) (xy 16.294862 -35.0393)
				)
			)
		)
		(zone
			(layer "F.Cu")
			(hatch none 0.5)
			(connect_pads
				(clearance 0)
			)
			(min_thickness 0.25)
			(keepout
				(tracks not_allowed)
				(vias allowed)
				(pads allowed)
				(copperpour not_allowed)
				(footprints allowed)
			)
			(placement
				(enabled no)
				(sheetname "")
			)
			(fill
				(thermal_gap 0.5)
				(thermal_bridge_width 0.5)
				(island_removal_mode 0)
			)
			(polygon
				(pts
					(xy 16.8021 -35.0393) (xy 16.8021 -35.420808) (xy 16.294862 -35.420808) (xy 16.294862 -35.0393)
				)
			)
		)
	)
)
